(kicad_pcb
	(version 20260206)
	(generator "pcbnew")
	(generator_version "10.0")
	(general
		(thickness 1.6)
		(legacy_teardrops no)
	)
	(paper "A4")
	(title_block
		(title "peb — Lightning_PEB_BRD.brd")
		(comment 1 "Lightning (Wiwynn / Facebook NVMe JBOF) / footprints 2544-2551 of 2563")
	)
	(layers
		(0 "F.Cu" signal "TOP")
		(4 "In1.Cu" signal "L2GND")
		(6 "In2.Cu" signal "L3")
		(8 "In3.Cu" signal "L4VCC")
		(10 "In4.Cu" signal "L5VCC")
		(12 "In5.Cu" signal "L6")
		(14 "In6.Cu" signal "L7GND")
		(2 "B.Cu" signal "BOTTOM")
		(9 "F.Adhes" user "F.Adhesive")
		(11 "B.Adhes" user "B.Adhesive")
		(13 "F.Paste" user "Package Geometry/Pastemask Top")
		(15 "B.Paste" user "Package Geometry/Pastemask Bottom")
		(5 "F.SilkS" user "Ref Des/Silkscreen Top")
		(7 "B.SilkS" user "Ref Des/Silkscreen Bottom")
		(1 "F.Mask" user "Board Geometry/Soldermask Top")
		(3 "B.Mask" user "Board Geometry/Soldermask Bottom")
		(17 "Dwgs.User" user "User.Drawings")
		(19 "Cmts.User" user "User.Comments")
		(21 "Eco1.User" user "User.Eco1")
		(23 "Eco2.User" user "User.Eco2")
		(25 "Edge.Cuts" user "Board Geometry/Outline")
		(27 "Margin" user)
		(31 "F.CrtYd" user "Package Geometry/Place Bound Top")
		(29 "B.CrtYd" user "Package Geometry/Place Bound Bottom")
		(35 "F.Fab" user "Ref Des/Assembly Top")
		(33 "B.Fab" user "Ref Des/Assembly Bottom")
	)
	(footprint ""
		(layer "B.Cu")
		(at 243.59997 -34.99993 -90)
		(property "Reference" "TP262"
			(at 0 0 90)
			(layer "B.SilkS")
			(hide yes)
			(effects
				(font
					(size 1.27 1.27)
				)
				(justify mirror)
			)
		)
		(property "Value" "TPAD28-2-GP"
			(at 0.0127 -1.6637 270)
			(unlocked yes)
			(layer "B.Fab")
			(hide yes)
			(effects
				(font
					(size 1.016 1.016)
					(thickness 0.1524)
				)
				(justify mirror)
			)
		)
		(property "Device Type" "TPAD28"
			(at 0.0127 -3.1877 270)
			(unlocked yes)
			(layer "B.Fab")
			(hide yes)
			(effects
				(font
					(size 1.016 1.016)
					(thickness 0.1524)
				)
				(justify mirror)
			)
		)
		(duplicate_pad_numbers_are_jumpers no)
		(fp_poly
			(pts
				(arc
					(start 0 -0.3556)
					(mid 0 0.3556)
					(end 0 -0.3556)
				)
			)
			(stroke
				(width 0)
				(type default)
			)
			(fill no)
			(layer "B.CrtYd")
		)
		(fp_poly
			(pts
				(arc
					(start 0 -0.6096)
					(mid 0 0.6096)
					(end 0 -0.6096)
				)
			)
			(stroke
				(width 0)
				(type default)
			)
			(fill no)
			(layer "B.Fab")
		)
		(pad "1" smd circle
			(at 0 0 90)
			(size 0.7112 0.7112)
			(layers "B.Cu" "B.Mask" "B.Paste")
			(net "LBI_DATA_4")
		)
	)
	(footprint ""
		(layer "B.Cu")
		(at 237.617 -59.99734 -90)
		(property "Reference" "C526"
			(at 0 0 90)
			(layer "B.SilkS")
			(hide yes)
			(effects
				(font
					(size 1.27 1.27)
				)
				(justify mirror)
			)
		)
		(property "Value" "SCD1U16V1KX-1-GP"
			(at 2.8321 -1.7399 270)
			(unlocked yes)
			(layer "B.Fab")
			(hide yes)
			(effects
				(font
					(size 1.016 1.016)
					(thickness 0.1524)
				)
				(justify mirror)
			)
		)
		(property "Device Type" "C0201H13"
			(at 2.8321 -3.2639 270)
			(unlocked yes)
			(layer "B.Fab")
			(hide yes)
			(effects
				(font
					(size 1.016 1.016)
					(thickness 0.1524)
				)
				(justify mirror)
			)
		)
		(duplicate_pad_numbers_are_jumpers no)
		(fp_rect
			(start 0.2794 0.6477)
			(end -0.2794 -0.6477)
			(stroke
				(width 0)
				(type default)
			)
			(fill no)
			(layer "B.CrtYd")
		)
		(fp_rect
			(start 0.2794 0.6477)
			(end -0.2794 -0.6477)
			(stroke
				(width 0)
				(type default)
			)
			(fill no)
			(layer "B.Fab")
		)
		(pad "1" smd custom
			(at 0 -0.2794 90)
			(size 0.0762 0.0762)
			(layers "B.Cu" "B.Mask" "B.Paste")
			(net "DUT_AVD_TX")
			(options
				(clearance outline)
				(anchor circle)
			)
			(primitives
				(gr_poly
					(pts
						(arc
							(start 0.1524 0.127)
							(mid 0.137521 0.162921)
							(end 0.1016 0.1778)
						)
						(arc
							(start -0.1016 0.1778)
							(mid -0.137521 0.162921)
							(end -0.1524 0.127)
						)
						(arc
							(start -0.1524 -0.127)
							(mid -0.137521 -0.162921)
							(end -0.1016 -0.1778)
						)
						(arc
							(start 0.1016 -0.1778)
							(mid 0.137521 -0.162921)
							(end 0.1524 -0.127)
						)
					)
					(width 0)
					(fill yes)
				)
			)
		)
		(pad "2" smd custom
			(at 0 0.2794 90)
			(size 0.0762 0.0762)
			(layers "B.Cu" "B.Mask" "B.Paste")
			(net "GND")
			(options
				(clearance outline)
				(anchor circle)
			)
			(primitives
				(gr_poly
					(pts
						(arc
							(start 0.1524 0.127)
							(mid 0.137521 0.162921)
							(end 0.1016 0.1778)
						)
						(arc
							(start -0.1016 0.1778)
							(mid -0.137521 0.162921)
							(end -0.1524 0.127)
						)
						(arc
							(start -0.1524 -0.127)
							(mid -0.137521 -0.162921)
							(end -0.1016 -0.1778)
						)
						(arc
							(start 0.1016 -0.1778)
							(mid 0.137521 -0.162921)
							(end 0.1524 -0.127)
						)
					)
					(width 0)
					(fill yes)
				)
			)
		)
	)
	(footprint ""
		(layer "B.Cu")
		(at 243.59997 -36.999926)
		(property "Reference" "TP210"
			(at 0 0 0)
			(layer "B.SilkS")
			(hide yes)
			(effects
				(font
					(size 1.27 1.27)
				)
				(justify mirror)
			)
		)
		(property "Value" "TPAD28-2-GP"
			(at 0.0127 -1.6637 0)
			(unlocked yes)
			(layer "B.Fab")
			(hide yes)
			(effects
				(font
					(size 1.016 1.016)
					(thickness 0.1524)
				)
				(justify mirror)
			)
		)
		(property "Device Type" "TPAD28"
			(at 0.0127 -3.1877 0)
			(unlocked yes)
			(layer "B.Fab")
			(hide yes)
			(effects
				(font
					(size 1.016 1.016)
					(thickness 0.1524)
				)
				(justify mirror)
			)
		)
		(duplicate_pad_numbers_are_jumpers no)
		(fp_poly
			(pts
				(arc
					(start 0.3556 0)
					(mid -0.3556 0)
					(end 0.3556 0)
				)
			)
			(stroke
				(width 0)
				(type default)
			)
			(fill no)
			(layer "B.CrtYd")
		)
		(fp_poly
			(pts
				(arc
					(start 0.6096 0)
					(mid -0.6096 0)
					(end 0.6096 0)
				)
			)
			(stroke
				(width 0)
				(type default)
			)
			(fill no)
			(layer "B.Fab")
		)
		(pad "1" smd circle
			(at 0 0 180)
			(size 0.7112 0.7112)
			(layers "B.Cu" "B.Mask" "B.Paste")
			(net "LBI_DATA_1")
		)
	)
	(footprint ""
		(layer "B.Cu")
		(at 20.955 -140.843 90)
		(property "Reference" "R299"
			(at 0 0 90)
			(layer "B.SilkS")
			(hide yes)
			(effects
				(font
					(size 1.27 1.27)
				)
				(justify mirror)
			)
		)
		(property "Value" "0R2J-2-GP"
			(at -0.064008 -3.993896 90)
			(unlocked yes)
			(layer "B.Fab")
			(hide yes)
			(effects
				(font
					(size 1.016 1.016)
					(thickness 0.1524)
				)
				(justify mirror)
			)
		)
		(property "Device Type" "R402H16"
			(at -0.064008 -5.517896 90)
			(unlocked yes)
			(layer "B.Fab")
			(hide yes)
			(effects
				(font
					(size 1.016 1.016)
					(thickness 0.1524)
				)
				(justify mirror)
			)
		)
		(duplicate_pad_numbers_are_jumpers no)
		(fp_line
			(start 0.508 -0.9398)
			(end 0.508 0.9398)
			(stroke
				(width 0.1524)
				(type default)
			)
			(layer "B.SilkS")
		)
		(fp_line
			(start -0.508 -0.9398)
			(end 0.508 -0.9398)
			(stroke
				(width 0.1524)
				(type default)
			)
			(layer "B.SilkS")
		)
		(fp_rect
			(start 0.508 0.9398)
			(end -0.508 -0.9398)
			(stroke
				(width 0)
				(type default)
			)
			(fill no)
			(layer "B.CrtYd")
		)
		(fp_rect
			(start 0.508 0.9398)
			(end -0.508 -0.9398)
			(stroke
				(width 0)
				(type default)
			)
			(fill no)
			(layer "B.Fab")
		)
		(pad "1" smd custom
			(at 0 -0.4445 270)
			(size 0.1397 0.1397)
			(layers "B.Cu" "B.Mask" "B.Paste")
			(net "FM_BMC_RESET_N")
			(options
				(clearance outline)
				(anchor circle)
			)
			(primitives
				(gr_poly
					(pts
						(arc
							(start -0.1778 0.2794)
							(mid -0.249642 0.249642)
							(end -0.2794 0.1778)
						)
						(arc
							(start -0.2794 -0.1778)
							(mid -0.249642 -0.249642)
							(end -0.1778 -0.2794)
						)
						(arc
							(start 0.1778 -0.2794)
							(mid 0.249642 -0.249642)
							(end 0.2794 -0.1778)
						)
						(arc
							(start 0.2794 0.1778)
							(mid 0.249642 0.249642)
							(end 0.1778 0.2794)
						)
					)
					(width 0)
					(fill yes)
				)
			)
		)
		(pad "2" smd custom
			(at 0 0.4445 270)
			(size 0.1397 0.1397)
			(layers "B.Cu" "B.Mask" "B.Paste")
			(net "BMC0_SRST_N")
			(options
				(clearance outline)
				(anchor circle)
			)
			(primitives
				(gr_poly
					(pts
						(arc
							(start -0.1778 0.2794)
							(mid -0.249642 0.249642)
							(end -0.2794 0.1778)
						)
						(arc
							(start -0.2794 -0.1778)
							(mid -0.249642 -0.249642)
							(end -0.1778 -0.2794)
						)
						(arc
							(start 0.1778 -0.2794)
							(mid 0.249642 -0.249642)
							(end 0.2794 -0.1778)
						)
						(arc
							(start 0.2794 0.1778)
							(mid 0.249642 0.249642)
							(end 0.1778 0.2794)
						)
					)
					(width 0)
					(fill yes)
				)
			)
		)
	)
	(footprint ""
		(layer "B.Cu")
		(at 127.680212 -205.849474)
		(property "Reference" "R3205"
			(at 0 0 0)
			(layer "B.SilkS")
			(hide yes)
			(effects
				(font
					(size 1.27 1.27)
				)
				(justify mirror)
			)
		)
		(property "Value" "0R2J-2-GP"
			(at -0.064008 -3.993896 0)
			(unlocked yes)
			(layer "B.Fab")
			(hide yes)
			(effects
				(font
					(size 1.016 1.016)
					(thickness 0.1524)
				)
				(justify mirror)
			)
		)
		(property "Device Type" "R402H16"
			(at -0.064008 -5.517896 0)
			(unlocked yes)
			(layer "B.Fab")
			(hide yes)
			(effects
				(font
					(size 1.016 1.016)
					(thickness 0.1524)
				)
				(justify mirror)
			)
		)
		(duplicate_pad_numbers_are_jumpers no)
		(fp_line
			(start -0.508 -0.9398)
			(end 0.508 -0.9398)
			(stroke
				(width 0.1524)
				(type default)
			)
			(layer "B.SilkS")
		)
		(fp_line
			(start 0.508 -0.9398)
			(end 0.508 0.9398)
			(stroke
				(width 0.1524)
				(type default)
			)
			(layer "B.SilkS")
		)
		(fp_rect
			(start 0.508 0.9398)
			(end -0.508 -0.9398)
			(stroke
				(width 0)
				(type default)
			)
			(fill no)
			(layer "B.CrtYd")
		)
		(fp_rect
			(start 0.508 0.9398)
			(end -0.508 -0.9398)
			(stroke
				(width 0)
				(type default)
			)
			(fill no)
			(layer "B.Fab")
		)
		(pad "1" smd custom
			(at 0 -0.4445 180)
			(size 0.1397 0.1397)
			(layers "B.Cu" "B.Mask" "B.Paste")
			(net "BMC_SSD_RST#1")
			(options
				(clearance outline)
				(anchor circle)
			)
			(primitives
				(gr_poly
					(pts
						(arc
							(start -0.1778 0.2794)
							(mid -0.249642 0.249642)
							(end -0.2794 0.1778)
						)
						(arc
							(start -0.2794 -0.1778)
							(mid -0.249642 -0.249642)
							(end -0.1778 -0.2794)
						)
						(arc
							(start 0.1778 -0.2794)
							(mid 0.249642 -0.249642)
							(end 0.2794 -0.1778)
						)
						(arc
							(start 0.2794 0.1778)
							(mid 0.249642 0.249642)
							(end 0.1778 0.2794)
						)
					)
					(width 0)
					(fill yes)
				)
			)
		)
		(pad "2" smd custom
			(at 0 0.4445 180)
			(size 0.1397 0.1397)
			(layers "B.Cu" "B.Mask" "B.Paste")
			(net "BMC_SSD_RST#0_A1")
			(options
				(clearance outline)
				(anchor circle)
			)
			(primitives
				(gr_poly
					(pts
						(arc
							(start -0.1778 0.2794)
							(mid -0.249642 0.249642)
							(end -0.2794 0.1778)
						)
						(arc
							(start -0.2794 -0.1778)
							(mid -0.249642 -0.249642)
							(end -0.1778 -0.2794)
						)
						(arc
							(start 0.1778 -0.2794)
							(mid 0.249642 -0.249642)
							(end 0.2794 -0.1778)
						)
						(arc
							(start 0.2794 0.1778)
							(mid 0.249642 0.249642)
							(end 0.1778 0.2794)
						)
					)
					(width 0)
					(fill yes)
				)
			)
		)
	)
	(footprint ""
		(layer "B.Cu")
		(at 74.594212 -192.641474)
		(property "Reference" "R3201"
			(at 0 0 0)
			(layer "B.SilkS")
			(hide yes)
			(effects
				(font
					(size 1.27 1.27)
				)
				(justify mirror)
			)
		)
		(property "Value" "0R2J-2-GP"
			(at -0.064008 -3.993896 0)
			(unlocked yes)
			(layer "B.Fab")
			(hide yes)
			(effects
				(font
					(size 1.016 1.016)
					(thickness 0.1524)
				)
				(justify mirror)
			)
		)
		(property "Device Type" "R402H16"
			(at -0.064008 -5.517896 0)
			(unlocked yes)
			(layer "B.Fab")
			(hide yes)
			(effects
				(font
					(size 1.016 1.016)
					(thickness 0.1524)
				)
				(justify mirror)
			)
		)
		(duplicate_pad_numbers_are_jumpers no)
		(fp_line
			(start -0.508 -0.9398)
			(end 0.508 -0.9398)
			(stroke
				(width 0.1524)
				(type default)
			)
			(layer "B.SilkS")
		)
		(fp_line
			(start 0.508 -0.9398)
			(end 0.508 0.9398)
			(stroke
				(width 0.1524)
				(type default)
			)
			(layer "B.SilkS")
		)
		(fp_rect
			(start 0.508 0.9398)
			(end -0.508 -0.9398)
			(stroke
				(width 0)
				(type default)
			)
			(fill no)
			(layer "B.CrtYd")
		)
		(fp_rect
			(start 0.508 0.9398)
			(end -0.508 -0.9398)
			(stroke
				(width 0)
				(type default)
			)
			(fill no)
			(layer "B.Fab")
		)
		(pad "1" smd custom
			(at 0 -0.4445 180)
			(size 0.1397 0.1397)
			(layers "B.Cu" "B.Mask" "B.Paste")
			(net "SSD_PERST#0")
			(options
				(clearance outline)
				(anchor circle)
			)
			(primitives
				(gr_poly
					(pts
						(arc
							(start -0.1778 0.2794)
							(mid -0.249642 0.249642)
							(end -0.2794 0.1778)
						)
						(arc
							(start -0.2794 -0.1778)
							(mid -0.249642 -0.249642)
							(end -0.1778 -0.2794)
						)
						(arc
							(start 0.1778 -0.2794)
							(mid 0.249642 -0.249642)
							(end 0.2794 -0.1778)
						)
						(arc
							(start 0.2794 0.1778)
							(mid 0.249642 0.249642)
							(end 0.1778 0.2794)
						)
					)
					(width 0)
					(fill yes)
				)
			)
		)
		(pad "2" smd custom
			(at 0 0.4445 180)
			(size 0.1397 0.1397)
			(layers "B.Cu" "B.Mask" "B.Paste")
			(net "SSD_PERST#0_B0")
			(options
				(clearance outline)
				(anchor circle)
			)
			(primitives
				(gr_poly
					(pts
						(arc
							(start -0.1778 0.2794)
							(mid -0.249642 0.249642)
							(end -0.2794 0.1778)
						)
						(arc
							(start -0.2794 -0.1778)
							(mid -0.249642 -0.249642)
							(end -0.1778 -0.2794)
						)
						(arc
							(start 0.1778 -0.2794)
							(mid 0.249642 -0.249642)
							(end 0.2794 -0.1778)
						)
						(arc
							(start 0.2794 0.1778)
							(mid 0.249642 0.249642)
							(end 0.1778 0.2794)
						)
					)
					(width 0)
					(fill yes)
				)
			)
		)
	)
	(footprint ""
		(layer "B.Cu")
		(at 234.595416 -60.1472)
		(property "Reference" "C541"
			(at 0 0 0)
			(layer "B.SilkS")
			(hide yes)
			(effects
				(font
					(size 1.27 1.27)
				)
				(justify mirror)
			)
		)
		(property "Value" "SCD1U16V1KX-1-GP"
			(at 2.8321 -1.7399 0)
			(unlocked yes)
			(layer "B.Fab")
			(hide yes)
			(effects
				(font
					(size 1.016 1.016)
					(thickness 0.1524)
				)
				(justify mirror)
			)
		)
		(property "Device Type" "C0201H13"
			(at 2.8321 -3.2639 0)
			(unlocked yes)
			(layer "B.Fab")
			(hide yes)
			(effects
				(font
					(size 1.016 1.016)
					(thickness 0.1524)
				)
				(justify mirror)
			)
		)
		(duplicate_pad_numbers_are_jumpers no)
		(fp_rect
			(start 0.2794 0.6477)
			(end -0.2794 -0.6477)
			(stroke
				(width 0)
				(type default)
			)
			(fill no)
			(layer "B.CrtYd")
		)
		(fp_rect
			(start 0.2794 0.6477)
			(end -0.2794 -0.6477)
			(stroke
				(width 0)
				(type default)
			)
			(fill no)
			(layer "B.Fab")
		)
		(pad "1" smd custom
			(at 0 -0.2794 180)
			(size 0.0762 0.0762)
			(layers "B.Cu" "B.Mask" "B.Paste")
			(net "DUT_AVD_PCIE")
			(options
				(clearance outline)
				(anchor circle)
			)
			(primitives
				(gr_poly
					(pts
						(arc
							(start 0.1524 0.127)
							(mid 0.137521 0.162921)
							(end 0.1016 0.1778)
						)
						(arc
							(start -0.1016 0.1778)
							(mid -0.137521 0.162921)
							(end -0.1524 0.127)
						)
						(arc
							(start -0.1524 -0.127)
							(mid -0.137521 -0.162921)
							(end -0.1016 -0.1778)
						)
						(arc
							(start 0.1016 -0.1778)
							(mid 0.137521 -0.162921)
							(end 0.1524 -0.127)
						)
					)
					(width 0)
					(fill yes)
				)
			)
		)
		(pad "2" smd custom
			(at 0 0.2794 180)
			(size 0.0762 0.0762)
			(layers "B.Cu" "B.Mask" "B.Paste")
			(net "GND")
			(options
				(clearance outline)
				(anchor circle)
			)
			(primitives
				(gr_poly
					(pts
						(arc
							(start 0.1524 0.127)
							(mid 0.137521 0.162921)
							(end 0.1016 0.1778)
						)
						(arc
							(start -0.1016 0.1778)
							(mid -0.137521 0.162921)
							(end -0.1524 0.127)
						)
						(arc
							(start -0.1524 -0.127)
							(mid -0.137521 -0.162921)
							(end -0.1016 -0.1778)
						)
						(arc
							(start 0.1016 -0.1778)
							(mid 0.137521 -0.162921)
							(end 0.1524 -0.127)
						)
					)
					(width 0)
					(fill yes)
				)
			)
		)
	)
	(footprint ""
		(layer "B.Cu")
		(at 241.6048 -59.99734 90)
		(property "Reference" "C527"
			(at 0 0 90)
			(layer "B.SilkS")
			(hide yes)
			(effects
				(font
					(size 1.27 1.27)
				)
				(justify mirror)
			)
		)
		(property "Value" "SCD1U16V1KX-1-GP"
			(at 2.8321 -1.7399 90)
			(unlocked yes)
			(layer "B.Fab")
			(hide yes)
			(effects
				(font
					(size 1.016 1.016)
					(thickness 0.1524)
				)
				(justify mirror)
			)
		)
		(property "Device Type" "C0201H13"
			(at 2.8321 -3.2639 90)
			(unlocked yes)
			(layer "B.Fab")
			(hide yes)
			(effects
				(font
					(size 1.016 1.016)
					(thickness 0.1524)
				)
				(justify mirror)
			)
		)
		(duplicate_pad_numbers_are_jumpers no)
		(fp_rect
			(start 0.2794 0.6477)
			(end -0.2794 -0.6477)
			(stroke
				(width 0)
				(type default)
			)
			(fill no)
			(layer "B.CrtYd")
		)
		(fp_rect
			(start 0.2794 0.6477)
			(end -0.2794 -0.6477)
			(stroke
				(width 0)
				(type default)
			)
			(fill no)
			(layer "B.Fab")
		)
		(pad "1" smd custom
			(at 0 -0.2794 270)
			(size 0.0762 0.0762)
			(layers "B.Cu" "B.Mask" "B.Paste")
			(net "DUT_AVD_TX")
			(options
				(clearance outline)
				(anchor circle)
			)
			(primitives
				(gr_poly
					(pts
						(arc
							(start 0.1524 0.127)
							(mid 0.137521 0.162921)
							(end 0.1016 0.1778)
						)
						(arc
							(start -0.1016 0.1778)
							(mid -0.137521 0.162921)
							(end -0.1524 0.127)
						)
						(arc
							(start -0.1524 -0.127)
							(mid -0.137521 -0.162921)
							(end -0.1016 -0.1778)
						)
						(arc
							(start 0.1016 -0.1778)
							(mid 0.137521 -0.162921)
							(end 0.1524 -0.127)
						)
					)
					(width 0)
					(fill yes)
				)
			)
		)
		(pad "2" smd custom
			(at 0 0.2794 270)
			(size 0.0762 0.0762)
			(layers "B.Cu" "B.Mask" "B.Paste")
			(net "GND")
			(options
				(clearance outline)
				(anchor circle)
			)
			(primitives
				(gr_poly
					(pts
						(arc
							(start 0.1524 0.127)
							(mid 0.137521 0.162921)
							(end 0.1016 0.1778)
						)
						(arc
							(start -0.1016 0.1778)
							(mid -0.137521 0.162921)
							(end -0.1524 0.127)
						)
						(arc
							(start -0.1524 -0.127)
							(mid -0.137521 -0.162921)
							(end -0.1016 -0.1778)
						)
						(arc
							(start 0.1016 -0.1778)
							(mid 0.137521 -0.162921)
							(end 0.1524 -0.127)
						)
					)
					(width 0)
					(fill yes)
				)
			)
		)
	)
)
